(kicad_pcb
	(version 20260206)
	(generator "pcbnew")
	(generator_version "10.0")
	(general
		(thickness 1.6)
		(legacy_teardrops no)
	)
	(paper "A4")
	(title_block
		(title "03242023_DA0F0TMBIJ0_F0T_Motherboard_J_brd_V01_OCP.brd")
		(comment 1 "Grand Teton / footprints 4212-4216 of 6105")
	)
	(layers
		(0 "F.Cu" signal "TOP")
		(4 "In1.Cu" signal "GND")
		(6 "In2.Cu" signal "IN1")
		(8 "In3.Cu" signal "GND1")
		(10 "In4.Cu" signal "IN2")
		(12 "In5.Cu" signal "GND2")
		(14 "In6.Cu" signal "IN3")
		(16 "In7.Cu" signal "GND3")
		(18 "In8.Cu" signal "VCC")
		(20 "In9.Cu" signal "VCC1")
		(22 "In10.Cu" signal "GND4")
		(24 "In11.Cu" signal "IN4")
		(26 "In12.Cu" signal "GND5")
		(28 "In13.Cu" signal "IN5")
		(30 "In14.Cu" signal "GND6")
		(32 "In15.Cu" signal "IN6")
		(34 "In16.Cu" signal "GND7")
		(2 "B.Cu" signal "BOTTOM")
		(9 "F.Adhes" user "F.Adhesive")
		(11 "B.Adhes" user "B.Adhesive")
		(13 "F.Paste" user "Package Geometry/Pastemask Top")
		(15 "B.Paste" user "Package Geometry/Pastemask Bottom")
		(5 "F.SilkS" user "Ref Des/Silkscreen Top")
		(7 "B.SilkS" user "Ref Des/Silkscreen Bottom")
		(1 "F.Mask" user "Board Geometry/Soldermask Top")
		(3 "B.Mask" user "Board Geometry/Soldermask Bottom")
		(17 "Dwgs.User" user "User.Drawings")
		(19 "Cmts.User" user "User.Comments")
		(21 "Eco1.User" user "User.Eco1")
		(23 "Eco2.User" user "User.Eco2")
		(25 "Edge.Cuts" user "Board Geometry/Outline")
		(27 "Margin" user)
		(31 "F.CrtYd" user "Package Geometry/Place Bound Top")
		(29 "B.CrtYd" user "Package Geometry/Place Bound Bottom")
		(35 "F.Fab" user "Ref Des/Assembly Top")
		(33 "B.Fab" user "Ref Des/Assembly Bottom")
	)
	(footprint ""
		(layer "B.Cu")
		(at 260.731508 -2.156206 180)
		(property "Reference" "J76"
			(at 4.218178 -1.140206 270)
			(unlocked yes)
			(layer "B.SilkS")
			(effects
				(font
					(size 0.7874 0.5842)
					(thickness 0.1524)
				)
				(justify left mirror)
			)
		)
		(property "Value" ""
			(at 0 0 0)
			(layer "B.Fab")
			(effects
				(font
					(size 1.27 1.27)
				)
				(justify mirror)
			)
		)
		(duplicate_pad_numbers_are_jumpers no)
		(fp_line
			(start 1.2192 2.1082)
			(end 1.2192 -2.1082)
			(stroke
				(width 0.1524)
				(type default)
			)
			(layer "B.SilkS")
		)
		(fp_line
			(start 1.2192 -2.1082)
			(end -1.2192 -2.1082)
			(stroke
				(width 0.1524)
				(type default)
			)
			(layer "B.SilkS")
		)
		(fp_line
			(start -1.2192 2.1082)
			(end 1.2192 2.1082)
			(stroke
				(width 0.1524)
				(type default)
			)
			(layer "B.SilkS")
		)
		(fp_line
			(start -1.2192 -2.1082)
			(end -1.2192 2.1082)
			(stroke
				(width 0.1524)
				(type default)
			)
			(layer "B.SilkS")
		)
		(pad "" np_thru_hole circle
			(at -3.4671 -1.27 90)
			(size 1.0414 1.0414)
			(drill 1.0414)
			(layers "*.Cu" "*.Mask")
			(clearance 0.381)
			(thermal_gap 0.381)
		)
		(pad "" np_thru_hole circle
			(at -3.4671 1.27 90)
			(size 1.0414 1.0414)
			(drill 1.0414)
			(layers "*.Cu" "*.Mask")
			(clearance 0.381)
			(thermal_gap 0.381)
		)
		(pad "" np_thru_hole circle
			(at 2.8829 -1.27 90)
			(size 1.0414 1.0414)
			(drill 1.0414)
			(layers "*.Cu" "*.Mask")
			(clearance 0.381)
			(thermal_gap 0.381)
		)
		(pad "" np_thru_hole circle
			(at 2.8829 1.27 90)
			(size 1.0414 1.0414)
			(drill 1.0414)
			(layers "*.Cu" "*.Mask")
			(clearance 0.381)
			(thermal_gap 0.381)
		)
		(pad "1" smd rect
			(at -0.8255 -0.249936 90)
			(size 0.3048 0.508)
			(layers "B.Cu" "B.Mask" "B.Paste")
			(net "DELTA_L_85_10INCH_BOT_DP")
		)
		(pad "2" smd rect
			(at -0.8255 0.249936 90)
			(size 0.3048 0.508)
			(layers "B.Cu" "B.Mask" "B.Paste")
			(net "DELTA_L_85_10INCH_BOT_DN")
		)
		(pad "3" smd circle
			(at 0 0)
			(size 0 0)
			(layers "B.Cu" "B.Mask" "B.Paste")
			(net "DELTA_L_GND_1")
		)
		(zone
			(layers "F.Cu" "B.Cu" "In1.Cu" "In2.Cu" "In3.Cu" "In4.Cu" "In5.Cu" "In6.Cu"
				"In7.Cu" "In8.Cu" "In9.Cu" "In10.Cu" "In11.Cu" "In12.Cu" "In13.Cu" "In14.Cu"
				"In15.Cu" "In16.Cu"
			)
			(hatch none 0.5)
			(connect_pads
				(clearance 0)
			)
			(min_thickness 0.25)
			(keepout
				(tracks not_allowed)
				(vias allowed)
				(pads allowed)
				(copperpour not_allowed)
				(footprints allowed)
			)
			(placement
				(enabled no)
				(sheetname "")
			)
			(fill
				(thermal_gap 0.5)
				(thermal_bridge_width 0.5)
				(island_removal_mode 0)
			)
			(polygon
				(pts
					(arc
						(start 258.775708 -3.426206)
						(mid 256.921508 -3.426206)
						(end 258.775708 -3.426206)
					)
				)
			)
		)
		(zone
			(layers "F.Cu" "B.Cu" "In1.Cu" "In2.Cu" "In3.Cu" "In4.Cu" "In5.Cu" "In6.Cu"
				"In7.Cu" "In8.Cu" "In9.Cu" "In10.Cu" "In11.Cu" "In12.Cu" "In13.Cu" "In14.Cu"
				"In15.Cu" "In16.Cu"
			)
			(hatch none 0.5)
			(connect_pads
				(clearance 0)
			)
			(min_thickness 0.25)
			(keepout
				(tracks not_allowed)
				(vias allowed)
				(pads allowed)
				(copperpour not_allowed)
				(footprints allowed)
			)
			(placement
				(enabled no)
				(sheetname "")
			)
			(fill
				(thermal_gap 0.5)
				(thermal_bridge_width 0.5)
				(island_removal_mode 0)
			)
			(polygon
				(pts
					(arc
						(start 258.775708 -0.886206)
						(mid 256.921508 -0.886206)
						(end 258.775708 -0.886206)
					)
				)
			)
		)
		(zone
			(layers "F.Cu" "B.Cu" "In1.Cu" "In2.Cu" "In3.Cu" "In4.Cu" "In5.Cu" "In6.Cu"
				"In7.Cu" "In8.Cu" "In9.Cu" "In10.Cu" "In11.Cu" "In12.Cu" "In13.Cu" "In14.Cu"
				"In15.Cu" "In16.Cu"
			)
			(hatch none 0.5)
			(connect_pads
				(clearance 0)
			)
			(min_thickness 0.25)
			(keepout
				(tracks not_allowed)
				(vias allowed)
				(pads allowed)
				(copperpour not_allowed)
				(footprints allowed)
			)
			(placement
				(enabled no)
				(sheetname "")
			)
			(fill
				(thermal_gap 0.5)
				(thermal_bridge_width 0.5)
				(island_removal_mode 0)
			)
			(polygon
				(pts
					(arc
						(start 265.125708 -3.426206)
						(mid 263.271508 -3.426206)
						(end 265.125708 -3.426206)
					)
				)
			)
		)
		(zone
			(layers "F.Cu" "B.Cu" "In1.Cu" "In2.Cu" "In3.Cu" "In4.Cu" "In5.Cu" "In6.Cu"
				"In7.Cu" "In8.Cu" "In9.Cu" "In10.Cu" "In11.Cu" "In12.Cu" "In13.Cu" "In14.Cu"
				"In15.Cu" "In16.Cu"
			)
			(hatch none 0.5)
			(connect_pads
				(clearance 0)
			)
			(min_thickness 0.25)
			(keepout
				(tracks not_allowed)
				(vias allowed)
				(pads allowed)
				(copperpour not_allowed)
				(footprints allowed)
			)
			(placement
				(enabled no)
				(sheetname "")
			)
			(fill
				(thermal_gap 0.5)
				(thermal_bridge_width 0.5)
				(island_removal_mode 0)
			)
			(polygon
				(pts
					(arc
						(start 265.125708 -0.886206)
						(mid 263.271508 -0.886206)
						(end 265.125708 -0.886206)
					)
				)
			)
		)
		(zone
			(layer "B.Cu")
			(hatch none 0.5)
			(connect_pads
				(clearance 0)
			)
			(min_thickness 0.25)
			(keepout
				(tracks not_allowed)
				(vias allowed)
				(pads allowed)
				(copperpour not_allowed)
				(footprints allowed)
			)
			(placement
				(enabled no)
				(sheetname "")
			)
			(fill
				(thermal_gap 0.5)
				(thermal_bridge_width 0.5)
				(island_removal_mode 0)
			)
			(polygon
				(pts
					(xy 261.849108 -1.607566) (xy 261.849108 -1.70307) (xy 261.252208 -1.70307) (xy 261.252208 -2.10947)
					(xy 261.849108 -2.10947) (xy 261.849108 -2.202942) (xy 261.252208 -2.202942) (xy 261.252208 -2.609342)
					(xy 261.849108 -2.609342) (xy 261.849108 -2.704846) (xy 261.150608 -2.704846) (xy 261.150608 -1.607566)
				)
			)
		)
	)
	(footprint ""
		(layer "B.Cu")
		(at 194.357752 -403.022054 -90)
		(property "Reference" "PR3910"
			(at 0 0 90)
			(layer "B.SilkS")
			(hide yes)
			(effects
				(font
					(size 1.27 1.27)
				)
				(justify mirror)
			)
		)
		(property "Value" ""
			(at 0 0 90)
			(layer "B.Fab")
			(effects
				(font
					(size 1.27 1.27)
				)
				(justify mirror)
			)
		)
		(duplicate_pad_numbers_are_jumpers no)
		(fp_line
			(start -0.7874 0.4064)
			(end 0.7874 0.4064)
			(stroke
				(width 0.1524)
				(type default)
			)
			(layer "B.SilkS")
		)
		(fp_line
			(start 0.7874 0.4064)
			(end 0.7874 -0.4064)
			(stroke
				(width 0.1524)
				(type default)
			)
			(layer "B.SilkS")
		)
		(fp_line
			(start -0.7874 -0.4064)
			(end -0.7874 0.4064)
			(stroke
				(width 0.1524)
				(type default)
			)
			(layer "B.SilkS")
		)
		(fp_line
			(start 0.7874 -0.4064)
			(end -0.7874 -0.4064)
			(stroke
				(width 0.1524)
				(type default)
			)
			(layer "B.SilkS")
		)
		(fp_line
			(start -0.67945 0.3048)
			(end -0.120396 0.3048)
			(stroke
				(width 0.1)
				(type default)
			)
			(layer "B.Fab")
		)
		(fp_line
			(start -0.120396 0.3048)
			(end -0.120396 0.2794)
			(stroke
				(width 0.1)
				(type default)
			)
			(layer "B.Fab")
		)
		(fp_line
			(start 0.12065 0.3048)
			(end 0.67945 0.3048)
			(stroke
				(width 0.1)
				(type default)
			)
			(layer "B.Fab")
		)
		(fp_line
			(start 0.67945 0.3048)
			(end 0.67945 -0.305054)
			(stroke
				(width 0.1)
				(type default)
			)
			(layer "B.Fab")
		)
		(fp_line
			(start -0.120396 0.2794)
			(end 0.12065 0.2794)
			(stroke
				(width 0.1)
				(type default)
			)
			(layer "B.Fab")
		)
		(fp_line
			(start 0.12065 0.2794)
			(end 0.12065 0.3048)
			(stroke
				(width 0.1)
				(type default)
			)
			(layer "B.Fab")
		)
		(fp_line
			(start -0.12065 -0.2794)
			(end -0.12065 -0.3048)
			(stroke
				(width 0.1)
				(type default)
			)
			(layer "B.Fab")
		)
		(fp_line
			(start 0.12065 -0.2794)
			(end -0.12065 -0.2794)
			(stroke
				(width 0.1)
				(type default)
			)
			(layer "B.Fab")
		)
		(fp_line
			(start -0.67945 -0.3048)
			(end -0.67945 0.3048)
			(stroke
				(width 0.1)
				(type default)
			)
			(layer "B.Fab")
		)
		(fp_line
			(start -0.12065 -0.3048)
			(end -0.67945 -0.3048)
			(stroke
				(width 0.1)
				(type default)
			)
			(layer "B.Fab")
		)
		(fp_line
			(start 0.12065 -0.305054)
			(end 0.12065 -0.2794)
			(stroke
				(width 0.1)
				(type default)
			)
			(layer "B.Fab")
		)
		(fp_line
			(start 0.67945 -0.305054)
			(end 0.12065 -0.305054)
			(stroke
				(width 0.1)
				(type default)
			)
			(layer "B.Fab")
		)
		(pad "1" smd circle
			(at 0.40005 0 90)
			(size 0 0)
			(layers "B.Cu" "B.Mask" "B.Paste")
			(net "HSC_VDD_R_1")
		)
		(pad "2" smd circle
			(at -0.40005 0 90)
			(size 0 0)
			(layers "B.Cu" "B.Mask" "B.Paste")
			(net "HSC_VDD")
		)
	)
	(footprint ""
		(layer "B.Cu")
		(at 290.948618 -149.992588 -90)
		(property "Reference" "R1821"
			(at 0 0 90)
			(layer "B.SilkS")
			(hide yes)
			(effects
				(font
					(size 1.27 1.27)
				)
				(justify mirror)
			)
		)
		(property "Value" ""
			(at 0 0 90)
			(layer "B.Fab")
			(effects
				(font
					(size 1.27 1.27)
				)
				(justify mirror)
			)
		)
		(duplicate_pad_numbers_are_jumpers no)
		(fp_line
			(start -0.7874 0.4064)
			(end 0.7874 0.4064)
			(stroke
				(width 0.1524)
				(type default)
			)
			(layer "B.SilkS")
		)
		(fp_line
			(start 0.7874 0.4064)
			(end 0.7874 -0.4064)
			(stroke
				(width 0.1524)
				(type default)
			)
			(layer "B.SilkS")
		)
		(fp_line
			(start -0.7874 -0.4064)
			(end -0.7874 0.4064)
			(stroke
				(width 0.1524)
				(type default)
			)
			(layer "B.SilkS")
		)
		(fp_line
			(start 0.7874 -0.4064)
			(end -0.7874 -0.4064)
			(stroke
				(width 0.1524)
				(type default)
			)
			(layer "B.SilkS")
		)
		(fp_line
			(start -0.67945 0.3048)
			(end -0.120396 0.3048)
			(stroke
				(width 0.1)
				(type default)
			)
			(layer "B.Fab")
		)
		(fp_line
			(start -0.120396 0.3048)
			(end -0.120396 0.2794)
			(stroke
				(width 0.1)
				(type default)
			)
			(layer "B.Fab")
		)
		(fp_line
			(start 0.12065 0.3048)
			(end 0.67945 0.3048)
			(stroke
				(width 0.1)
				(type default)
			)
			(layer "B.Fab")
		)
		(fp_line
			(start 0.67945 0.3048)
			(end 0.67945 -0.305054)
			(stroke
				(width 0.1)
				(type default)
			)
			(layer "B.Fab")
		)
		(fp_line
			(start -0.120396 0.2794)
			(end 0.12065 0.2794)
			(stroke
				(width 0.1)
				(type default)
			)
			(layer "B.Fab")
		)
		(fp_line
			(start 0.12065 0.2794)
			(end 0.12065 0.3048)
			(stroke
				(width 0.1)
				(type default)
			)
			(layer "B.Fab")
		)
		(fp_line
			(start -0.12065 -0.2794)
			(end -0.12065 -0.3048)
			(stroke
				(width 0.1)
				(type default)
			)
			(layer "B.Fab")
		)
		(fp_line
			(start 0.12065 -0.2794)
			(end -0.12065 -0.2794)
			(stroke
				(width 0.1)
				(type default)
			)
			(layer "B.Fab")
		)
		(fp_line
			(start -0.67945 -0.3048)
			(end -0.67945 0.3048)
			(stroke
				(width 0.1)
				(type default)
			)
			(layer "B.Fab")
		)
		(fp_line
			(start -0.12065 -0.3048)
			(end -0.67945 -0.3048)
			(stroke
				(width 0.1)
				(type default)
			)
			(layer "B.Fab")
		)
		(fp_line
			(start 0.12065 -0.305054)
			(end 0.12065 -0.2794)
			(stroke
				(width 0.1)
				(type default)
			)
			(layer "B.Fab")
		)
		(fp_line
			(start 0.67945 -0.305054)
			(end 0.12065 -0.305054)
			(stroke
				(width 0.1)
				(type default)
			)
			(layer "B.Fab")
		)
		(pad "1" smd circle
			(at 0.40005 0 90)
			(size 0 0)
			(layers "B.Cu" "B.Mask" "B.Paste")
			(net "FM_SPD_REMOTE_EN_R")
		)
		(pad "2" smd circle
			(at -0.40005 0 90)
			(size 0 0)
			(layers "B.Cu" "B.Mask" "B.Paste")
			(net "FM_SPD_REMOTE_EN")
		)
	)
	(footprint ""
		(layer "B.Cu")
		(at 308.902608 -250.785376 90)
		(property "Reference" "C520"
			(at 0 0 90)
			(layer "B.SilkS")
			(hide yes)
			(effects
				(font
					(size 1.27 1.27)
				)
				(justify mirror)
			)
		)
		(property "Value" ""
			(at 0 0 90)
			(layer "B.Fab")
			(effects
				(font
					(size 1.27 1.27)
				)
				(justify mirror)
			)
		)
		(duplicate_pad_numbers_are_jumpers no)
		(fp_line
			(start 1.524 -0.762)
			(end -1.524 -0.762)
			(stroke
				(width 0.1524)
				(type default)
			)
			(layer "B.SilkS")
		)
		(fp_line
			(start -1.524 -0.762)
			(end -1.524 0.762)
			(stroke
				(width 0.1524)
				(type default)
			)
			(layer "B.SilkS")
		)
		(fp_line
			(start 1.524 0.762)
			(end 1.524 -0.762)
			(stroke
				(width 0.1524)
				(type default)
			)
			(layer "B.SilkS")
		)
		(fp_line
			(start -1.524 0.762)
			(end 1.524 0.762)
			(stroke
				(width 0.1524)
				(type default)
			)
			(layer "B.SilkS")
		)
		(fp_line
			(start 1.1049 -0.724916)
			(end 1.1049 0.724916)
			(stroke
				(width 0.1)
				(type default)
			)
			(layer "B.Fab")
		)
		(fp_line
			(start -1.1049 -0.724916)
			(end 1.1049 -0.724916)
			(stroke
				(width 0.1)
				(type default)
			)
			(layer "B.Fab")
		)
		(fp_line
			(start 1.1049 0.724916)
			(end -1.1049 0.724916)
			(stroke
				(width 0.1)
				(type default)
			)
			(layer "B.Fab")
		)
		(fp_line
			(start -1.1049 0.724916)
			(end -1.1049 -0.724916)
			(stroke
				(width 0.1)
				(type default)
			)
			(layer "B.Fab")
		)
		(pad "1" smd rect
			(at 0.889 0 90)
			(size 1.016 1.27)
			(layers "B.Cu" "B.Mask" "B.Paste")
			(net "PVCCFA_EHV_FIVRA_CPU0")
		)
		(pad "2" smd rect
			(at -0.889 0 90)
			(size 1.016 1.27)
			(layers "B.Cu" "B.Mask" "B.Paste")
			(net "GND")
		)
	)
	(footprint ""
		(layer "B.Cu")
		(at 15.433294 -110.987586 90)
		(property "Reference" "C5234"
			(at 0 0 90)
			(layer "B.SilkS")
			(hide yes)
			(effects
				(font
					(size 1.27 1.27)
				)
				(justify mirror)
			)
		)
		(property "Value" ""
			(at 0 0 90)
			(layer "B.Fab")
			(effects
				(font
					(size 1.27 1.27)
				)
				(justify mirror)
			)
		)
		(duplicate_pad_numbers_are_jumpers no)
		(fp_line
			(start 0.7874 -0.4064)
			(end -0.7874 -0.4064)
			(stroke
				(width 0.1524)
				(type default)
			)
			(layer "B.SilkS")
		)
		(fp_line
			(start -0.7874 -0.4064)
			(end -0.7874 0.4064)
			(stroke
				(width 0.1524)
				(type default)
			)
			(layer "B.SilkS")
		)
		(fp_line
			(start 0.7874 0.4064)
			(end 0.7874 -0.4064)
			(stroke
				(width 0.1524)
				(type default)
			)
			(layer "B.SilkS")
		)
		(fp_line
			(start -0.7874 0.4064)
			(end 0.7874 0.4064)
			(stroke
				(width 0.1524)
				(type default)
			)
			(layer "B.SilkS")
		)
		(fp_line
			(start 0.67945 -0.305054)
			(end 0.12065 -0.305054)
			(stroke
				(width 0.1)
				(type default)
			)
			(layer "B.Fab")
		)
		(fp_line
			(start 0.12065 -0.305054)
			(end 0.12065 -0.2794)
			(stroke
				(width 0.1)
				(type default)
			)
			(layer "B.Fab")
		)
		(fp_line
			(start -0.12065 -0.3048)
			(end -0.67945 -0.3048)
			(stroke
				(width 0.1)
				(type default)
			)
			(layer "B.Fab")
		)
		(fp_line
			(start -0.67945 -0.3048)
			(end -0.67945 0.3048)
			(stroke
				(width 0.1)
				(type default)
			)
			(layer "B.Fab")
		)
		(fp_line
			(start 0.12065 -0.2794)
			(end -0.12065 -0.2794)
			(stroke
				(width 0.1)
				(type default)
			)
			(layer "B.Fab")
		)
		(fp_line
			(start -0.12065 -0.2794)
			(end -0.12065 -0.3048)
			(stroke
				(width 0.1)
				(type default)
			)
			(layer "B.Fab")
		)
		(fp_line
			(start 0.12065 0.2794)
			(end 0.12065 0.3048)
			(stroke
				(width 0.1)
				(type default)
			)
			(layer "B.Fab")
		)
		(fp_line
			(start -0.120396 0.2794)
			(end 0.12065 0.2794)
			(stroke
				(width 0.1)
				(type default)
			)
			(layer "B.Fab")
		)
		(fp_line
			(start 0.67945 0.3048)
			(end 0.67945 -0.305054)
			(stroke
				(width 0.1)
				(type default)
			)
			(layer "B.Fab")
		)
		(fp_line
			(start 0.12065 0.3048)
			(end 0.67945 0.3048)
			(stroke
				(width 0.1)
				(type default)
			)
			(layer "B.Fab")
		)
		(fp_line
			(start -0.120396 0.3048)
			(end -0.120396 0.2794)
			(stroke
				(width 0.1)
				(type default)
			)
			(layer "B.Fab")
		)
		(fp_line
			(start -0.67945 0.3048)
			(end -0.120396 0.3048)
			(stroke
				(width 0.1)
				(type default)
			)
			(layer "B.Fab")
		)
		(pad "1" smd circle
			(at 0.40005 0 270)
			(size 0 0)
			(layers "B.Cu" "B.Mask" "B.Paste")
			(net "P3V3_AUX")
		)
		(pad "2" smd circle
			(at -0.40005 0 270)
			(size 0 0)
			(layers "B.Cu" "B.Mask" "B.Paste")
			(net "GND")
		)
	)
)
